# S9S_MB_2U (Grand Teton) — schematic netlist excerpt (pin names and nets, part order shuffled) for the footprints in the layout excerpt that follows; sources: Cadence DE-HDL packaged netlist, KiCad conversion of 03242023_DA0F0TMBIJ0_F0T_Motherboard_J_brd_V01_OCP.brd

J30  SCONN288_ADR50017P087CC  SCONN288_ADR50017-P087CC IO  pkg DDR288S_1-1VXB  page 111
  VIN_BULK0  = P12V_S3_AUX_CPU1_NVDIMM
  RFU0  = TP_CHG_CPU1_DIMM2_FRU_0
  VIN_MGMT  = P3V3_AUX
  HSCL  = I3C_SPD_DDREFGH_CPU1_LVC1_SCL_5
  HSDA  = I3C_SPD_DDREFGH_CPU1_LVC1_SDA
  VSS0  = GND
  DQ0_A  = M_G_CPU1_SA_DQ<0>
  VSS1  = GND
  DQ1_A  = M_G_CPU1_SA_DQ<1>
  VSS2  = GND
  DQS0_A_T  = M_G_CPU1_SA_DQS_DP<0>
  DQS0_A_C  = M_G_CPU1_SA_DQS_DN<0>
  VSS3  = GND
  DQ4_A  = M_G_CPU1_SA_DQ<4>
  VSS4  = GND
  DQ5_A  = M_G_CPU1_SA_DQ<5>
  VSS5  = GND
  DQ8_A  = M_G_CPU1_SA_DQ<8>
  VSS6  = GND
  DQ9_A  = M_G_CPU1_SA_DQ<9>
  VSS7  = GND
  DQS1_A_T  = M_G_CPU1_SA_DQS_DP<1>
  DQS1_A_C  = M_G_CPU1_SA_DQS_DN<1>
  VSS8  = GND
  DQ12_A  = M_G_CPU1_SA_DQ<12>
  VSS9  = GND
  DQ13_A  = M_G_CPU1_SA_DQ<13>
  VSS10  = GND
  DQ16_A  = M_G_CPU1_SA_DQ<16>
  VSS11  = GND
  DQ17_A  = M_G_CPU1_SA_DQ<17>
  VSS12  = GND
  DQS2_A_T  = M_G_CPU1_SA_DQS_DP<2>
  DQS2_A_C  = M_G_CPU1_SA_DQS_DN<2>
  VSS13  = GND
  DQ20_A  = M_G_CPU1_SA_DQ<20>
  VSS14  = GND
  DQ21_A  = M_G_CPU1_SA_DQ<21>
  VSS15  = GND
  DQ24_A  = M_G_CPU1_SA_DQ<24>
  VSS16  = GND
  DQ25_A  = M_G_CPU1_SA_DQ<25>
  VSS17  = GND
  DQS3_A_T  = M_G_CPU1_SA_DQS_DP<3>
  DQS3_A_C  = M_G_CPU1_SA_DQS_DN<3>
  VSS18  = GND
  DQ28_A  = M_G_CPU1_SA_DQ<28>
  VSS19  = GND
  DQ29_A  = M_G_CPU1_SA_DQ<29>
  VSS20  = GND
  CB0_A  = M_G_CPU1_SA_CB<0>
  VSS21  = GND
  CB1_A  = M_G_CPU1_SA_CB<1>
  VSS22  = GND
  DQS4_A_T  = M_G_CPU1_SA_DQS_DP<4>
  DQS4_A_C  = M_G_CPU1_SA_DQS_DN<4>
  VSS23  = GND
  CB4_A  = M_G_CPU1_SA_CB<4>
  VSS24  = GND
  CB5_A  = M_G_CPU1_SA_CB<5>
  VSS25  = GND
  ALERT_N  = M_G_CPU1_ALERT_N
  VSS26  = GND
  CS0_A_N  = M_G_CPU1_SA_CS_N<2>
  VSS27  = GND
  CA0_A  = M_G_CPU1_SA_CA<0>
  VSS28  = GND
  CA2_A  = M_G_CPU1_SA_CA<2>
  VSS29  = GND
  CA4_A  = M_G_CPU1_SA_CA<4>
  VSS30  = GND
  CA6_A  = M_G_CPU1_SA_CA<6>
  VSS31  = GND
  PAR_A  = M_G_CPU1_SA_PAR
  VSS32  = GND
  CA0_B  = M_G_CPU1_SB_CA<0>
  VSS33  = GND
  CA2_B  = M_G_CPU1_SB_CA<2>
  VSS34  = GND
  CA4_B  = M_G_CPU1_SB_CA<4>
  VSS35  = GND
  CA6_B  = M_G_CPU1_SB_CA<6>
  VSS36  = GND
  CS0_B_N  = M_G_CPU1_SB_CS_N<2>
  VSS37  = GND
  \lbd||rsp_a_n\  = M_G_CPU1_SA_RSP<1>
  \lbs||rsp_b_n\  = M_G_CPU1_SB_RSP<1>
  VSS38  = GND
  CB4_B  = M_G_CPU1_SB_CB<4>
  VSS39  = GND
  CB5_B  = M_G_CPU1_SB_CB<5>
  VSS40  = GND
  \dqs9_b_t||tdqs9_b_t||dbi4_b_n\  = M_G_CPU1_SB_DQS_DP<9>
  \dqs9_b_c||tdqs9_b_c\  = M_G_CPU1_SB_DQS_DN<9>
  VSS41  = GND
  CB0_B  = M_G_CPU1_SB_CB<0>
  VSS42  = GND
  CB1_B  = M_G_CPU1_SB_CB<1>
  VSS43  = GND
  DQ0_B  = M_G_CPU1_SB_DQ<0>
  VSS44  = GND
  DQ1_B  = M_G_CPU1_SB_DQ<1>
  VSS45  = GND
  DQS0_B_T  = M_G_CPU1_SB_DQS_DP<0>
  DQS0_B_C  = M_G_CPU1_SB_DQS_DN<0>
  VSS46  = GND
  DQ4_B  = M_G_CPU1_SB_DQ<4>
  VSS47  = GND
  DQ5_B  = M_G_CPU1_SB_DQ<5>
  VSS48  = GND
  DQ8_B  = M_G_CPU1_SB_DQ<8>
  VSS49  = GND
  DQ9_B  = M_G_CPU1_SB_DQ<9>
  VSS50  = GND
  DQS1_B_T  = M_G_CPU1_SB_DQS_DP<1>
  DQS1_B_C  = M_G_CPU1_SB_DQS_DN<1>
  VSS51  = GND
  DQ12_B  = M_G_CPU1_SB_DQ<12>
  VSS52  = GND
  DQ13_B  = M_G_CPU1_SB_DQ<13>
  VSS53  = GND
  DQ16_B  = M_G_CPU1_SB_DQ<16>
  VSS54  = GND
  DQ17_B  = M_G_CPU1_SB_DQ<17>
  VSS55  = GND
  DQS2_B_T  = M_G_CPU1_SB_DQS_DP<2>
  DQS2_B_C  = M_G_CPU1_SB_DQS_DN<2>
  VSS56  = GND
  DQ20_B  = M_G_CPU1_SB_DQ<20>
  VSS57  = GND
  DQ21_B  = M_G_CPU1_SB_DQ<21>
  VSS58  = GND
  DQ24_B  = M_G_CPU1_SB_DQ<24>
  VSS59  = GND
  DQ25_B  = M_G_CPU1_SB_DQ<25>
  VSS60  = GND
  DQS3_B_T  = M_G_CPU1_SB_DQS_DP<3>
  DQS3_B_C  = M_G_CPU1_SB_DQS_DN<3>
  VSS61  = GND
  DQ28_B  = M_G_CPU1_SB_DQ<28>
  VSS62  = GND
  DQ29_B  = M_G_CPU1_SB_DQ<29>
  VSS63  = GND
  RFU1  = TP_CHG_CPU1_DIMM2_FRU_1
  VIN_BULK1  = P12V_S3_AUX_CPU1_NVDIMM
  VIN_BULK2  = P12V_S3_AUX_CPU1_NVDIMM
  \pwr_good||fail_n\  = PWRGD_CHG_CPU1_DIMM2
  HSA  = PD_CHG_CPU1_DIMM2_SAA
  RFU2  = TP_CHG_CPU1_DIMM2_FRU_2
  RFU3  = TP_CHG_CPU1_DIMM2_FRU_3
  VSS64  = GND
  DQ2_A  = M_G_CPU1_SA_DQ<2>
  VSS65  = GND
  DQ3_A  = M_G_CPU1_SA_DQ<3>
  VSS66  = GND
  \dqs5_a_c||tdqs5_a_c||dqs5_a_t||tdqs5_a_t\  = M_G_CPU1_SA_DQS_DN<5>
  \dqs5_a_t||tdqs5_a_t\  = M_G_CPU1_SA_DQS_DP<5>
  VSS67  = GND
  DQ6_A  = M_G_CPU1_SA_DQ<6>
  VSS68  = GND
  DQ7_A  = M_G_CPU1_SA_DQ<7>
  VSS69  = GND
  DQ10_A  = M_G_CPU1_SA_DQ<10>
  VSS70  = GND
  DQ11_A  = M_G_CPU1_SA_DQ<11>
  VSS71  = GND
  \dqs6_a_c||tdqs6_a_c||dqs6_a_t||tdqs6_a_t\  = M_G_CPU1_SA_DQS_DN<6>
  \dqs6_a_t||tdqs6_a_t\  = M_G_CPU1_SA_DQS_DP<6>
  VSS72  = GND
  DQ14_A  = M_G_CPU1_SA_DQ<14>
  VSS73  = GND
  DQ15_A  = M_G_CPU1_SA_DQ<15>
  VSS74  = GND
  DQ18_A  = M_G_CPU1_SA_DQ<18>
  VSS75  = GND
  DQ19_A  = M_G_CPU1_SA_DQ<19>
  VSS76  = GND
  \dqs7_a_c||tdqs7_a_c\  = M_G_CPU1_SA_DQS_DN<7>
  \dqs7_a_t||tdqs7_a_t\  = M_G_CPU1_SA_DQS_DP<7>
  VSS77  = GND
  DQ22_A  = M_G_CPU1_SA_DQ<22>
  VSS78  = GND
  DQ23_A  = M_G_CPU1_SA_DQ<23>
  VSS79  = GND
  DQ26_A  = M_G_CPU1_SA_DQ<26>
  VSS80  = GND
  DQ27_A  = M_G_CPU1_SA_DQ<27>
  VSS81  = GND
  \dqs8_a_c||tdqs8_a_c\  = M_G_CPU1_SA_DQS_DN<8>
  \dqs8_a_t||tdqs8_a_t\  = M_G_CPU1_SA_DQS_DP<8>
  VSS82  = GND
  DQ30_A  = M_G_CPU1_SA_DQ<30>
  VSS83  = GND
  DQ31_A  = M_G_CPU1_SA_DQ<31>
  VSS84  = GND
  CB2_A  = M_G_CPU1_SA_CB<2>
  VSS85  = GND
  CB3_A  = M_G_CPU1_SA_CB<3>
  VSS86  = GND
  \dqs9_a_c||tdqs9_a_c\  = M_G_CPU1_SA_DQS_DN<9>
  \dqs9_a_t||tdqs9_a_t\  = M_G_CPU1_SA_DQS_DP<9>
  VSS87  = GND
  CB6_A  = M_G_CPU1_SA_CB<6>
  VSS88  = GND
  CB7_A  = M_G_CPU1_SA_CB<7>
  VSS89  = GND
  RESET_N  = RST_M_GH_CPU1_FPGA_N
  VSS90  = GND
  CS1_A_N  = M_G_CPU1_SA_CS_N<3>
  VSS91  = GND
  CA1_A  = M_G_CPU1_SA_CA<1>
  VSS92  = GND
  CA3_A  = M_G_CPU1_SA_CA<3>
  VSS93  = GND
  CA5_A  = M_G_CPU1_SA_CA<5>
  VSS94  = GND
  CK_T  = M_G_CPU1_CLK_DP<1>
  CK_C  = M_G_CPU1_CLK_DN<1>
  VSS95  = GND
  RFU4  = TP_CHG_CPU1_DIMM2_FRU_4
  CA1_B  = M_G_CPU1_SB_CA<1>
  VSS96  = GND
  CA3_B  = M_G_CPU1_SB_CA<3>
  VSS97  = GND
  CA5_B  = M_G_CPU1_SB_CA<5>
  VSS98  = GND
  PAR_B  = M_G_CPU1_SB_PAR
  VSS99  = GND
  CS1_B_N  = M_G_CPU1_SB_CS_N<3>
  VSS100  = GND
  RFU5  = TP_CHG_CPU1_DIMM2_FRU_5
  RFU6  = TP_CHG_CPU1_DIMM2_FRU_6
  VSS101  = GND
  CB6_B  = M_G_CPU1_SB_CB<6>
  VSS102  = GND
  CB7_B  = M_G_CPU1_SB_CB<7>
  VSS103  = GND
  DQS4_B_C  = M_G_CPU1_SB_DQS_DN<4>
  DQS4_B_T  = M_G_CPU1_SB_DQS_DP<4>
  VSS104  = GND
  CB2_B  = M_G_CPU1_SB_CB<2>
  VSS105  = GND
  CB3_B  = M_G_CPU1_SB_CB<3>
  VSS106  = GND
  DQ2_B  = M_G_CPU1_SB_DQ<2>
  VSS107  = GND
  DQ3_B  = M_G_CPU1_SB_DQ<3>
  VSS108  = GND
  \dqs5_b_c||tdqs5_b_c\  = M_G_CPU1_SB_DQS_DN<5>
  \dqs5_b_t||tdqs5_b_t\  = M_G_CPU1_SB_DQS_DP<5>
  VSS109  = GND
  DQ6_B  = M_G_CPU1_SB_DQ<6>
  VSS110  = GND
  DQ7_B  = M_G_CPU1_SB_DQ<7>
  VSS111  = GND
  DQ10_B  = M_G_CPU1_SB_DQ<10>
  VSS112  = GND
  DQ11_B  = M_G_CPU1_SB_DQ<11>
  VSS113  = GND
  \dqs6_b_c||tdqs6_b_c\  = M_G_CPU1_SB_DQS_DN<6>
  \dqs6_b_t||tdqs6_b_t\  = M_G_CPU1_SB_DQS_DP<6>
  VSS114  = GND
  DQ14_B  = M_G_CPU1_SB_DQ<14>
  VSS115  = GND
  DQ15_B  = M_G_CPU1_SB_DQ<15>
  VSS116  = GND
  DQ18_B  = M_G_CPU1_SB_DQ<18>
  VSS117  = GND
  DQ19_B  = M_G_CPU1_SB_DQ<19>
  VSS118  = GND
  \dqs7_b_c||tdqs7_b_c\  = M_G_CPU1_SB_DQS_DN<7>
  \dqs7_b_t||tdqs7_b_t\  = M_G_CPU1_SB_DQS_DP<7>
  VSS119  = GND
  DQ22_B  = M_G_CPU1_SB_DQ<22>
  VSS120  = GND
  DQ23_B  = M_G_CPU1_SB_DQ<23>
  VSS121  = GND
  DQ26_B  = M_G_CPU1_SB_DQ<26>
  VSS122  = GND
  DQ27_B  = M_G_CPU1_SB_DQ<27>
  VSS123  = GND
  \dqs8_b_c||tdqs8_b_c\  = M_G_CPU1_SB_DQS_DN<8>
  \dqs8_b_t||tdqs8_b_t\  = M_G_CPU1_SB_DQS_DP<8>
  VSS124  = GND
  DQ30_B  = M_G_CPU1_SB_DQ<30>
  VSS125  = GND
  DQ31_B  = M_G_CPU1_SB_DQ<31>
  VSS126  = GND
  G1  = GND
  G2  = GND
  G3  = GND

(kicad_pcb
	(version 20260206)
	(generator "pcbnew")
	(generator_version "10.0")
	(general
		(thickness 1.6)
		(legacy_teardrops no)
	)
	(paper "A4")
	(title_block
		(title "03242023_DA0F0TMBIJ0_F0T_Motherboard_J_brd_V01_OCP.brd")
		(comment 1 "Grand Teton / footprint 1354 of 6105 (J30), pads 138-182 of 291")
	)
	(layers
		(0 "F.Cu" signal "TOP")
		(4 "In1.Cu" signal "GND")
		(6 "In2.Cu" signal "IN1")
		(8 "In3.Cu" signal "GND1")
		(10 "In4.Cu" signal "IN2")
		(12 "In5.Cu" signal "GND2")
		(14 "In6.Cu" signal "IN3")
		(16 "In7.Cu" signal "GND3")
		(18 "In8.Cu" signal "VCC")
		(20 "In9.Cu" signal "VCC1")
		(22 "In10.Cu" signal "GND4")
		(24 "In11.Cu" signal "IN4")
		(26 "In12.Cu" signal "GND5")
		(28 "In13.Cu" signal "IN5")
		(30 "In14.Cu" signal "GND6")
		(32 "In15.Cu" signal "IN6")
		(34 "In16.Cu" signal "GND7")
		(2 "B.Cu" signal "BOTTOM")
		(9 "F.Adhes" user "F.Adhesive")
		(11 "B.Adhes" user "B.Adhesive")
		(13 "F.Paste" user "Package Geometry/Pastemask Top")
		(15 "B.Paste" user "Package Geometry/Pastemask Bottom")
		(5 "F.SilkS" user "Ref Des/Silkscreen Top")
		(7 "B.SilkS" user "Ref Des/Silkscreen Bottom")
		(1 "F.Mask" user "Board Geometry/Soldermask Top")
		(3 "B.Mask" user "Board Geometry/Soldermask Bottom")
		(17 "Dwgs.User" user "User.Drawings")
		(19 "Cmts.User" user "User.Comments")
		(21 "Eco1.User" user "User.Eco1")
		(23 "Eco2.User" user "User.Eco2")
		(25 "Edge.Cuts" user "Board Geometry/Outline")
		(27 "Margin" user)
		(31 "F.CrtYd" user "Package Geometry/Place Bound Top")
		(29 "B.CrtYd" user "Package Geometry/Place Bound Bottom")
		(35 "F.Fab" user "Ref Des/Assembly Top")
		(33 "B.Fab" user "Ref Des/Assembly Bottom")
	)
	(footprint ""
		(layer "F.Cu")
		(at 191.03848 -258.091686)
		(property "Reference" "J30"
			(at -2.98196 -81.740248 0)
			(unlocked yes)
			(layer "F.SilkS")
			(effects
				(font
					(size 0.7874 0.5842)
					(thickness 0.1524)
				)
				(justify left)
			)
		)
		(property "Value" ""
			(at 0 0 0)
			(layer "F.Fab")
			(effects
				(font
					(size 1.27 1.27)
				)
			)
		)
		(duplicate_pad_numbers_are_jumpers no)
		(pad "138" smd rect
			(at -2.050034 58.224928 270)
			(size 0.519938 1.4986)
			(layers "F.Cu" "F.Mask" "F.Paste")
			(net "M_G_CPU1_SB_DQS_DN<3>")
		)
		(pad "139" smd rect
			(at -2.050034 59.075066 270)
			(size 0.519938 1.4986)
			(layers "F.Cu" "F.Mask" "F.Paste")
			(net "GND")
		)
		(pad "140" smd rect
			(at -2.050034 59.92495 270)
			(size 0.519938 1.4986)
			(layers "F.Cu" "F.Mask" "F.Paste")
			(net "M_G_CPU1_SB_DQ<28>")
		)
		(pad "141" smd rect
			(at -2.050034 60.775088 270)
			(size 0.519938 1.4986)
			(layers "F.Cu" "F.Mask" "F.Paste")
			(net "GND")
		)
		(pad "142" smd rect
			(at -2.050034 61.624972 270)
			(size 0.519938 1.4986)
			(layers "F.Cu" "F.Mask" "F.Paste")
			(net "M_G_CPU1_SB_DQ<29>")
		)
		(pad "143" smd rect
			(at -2.050034 62.47511 270)
			(size 0.519938 1.4986)
			(layers "F.Cu" "F.Mask" "F.Paste")
			(net "GND")
		)
		(pad "144" smd rect
			(at -2.050034 63.324994 270)
			(size 0.519938 1.4986)
			(layers "F.Cu" "F.Mask" "F.Paste")
			(net "TP_CHG_CPU1_DIMM2_FRU_1")
		)
		(pad "145" smd rect
			(at 2.050034 -63.324994 270)
			(size 0.519938 1.4986)
			(layers "F.Cu" "F.Mask" "F.Paste")
			(net "P12V_S3_AUX_CPU1_NVDIMM")
		)
		(pad "146" smd rect
			(at 2.050034 -62.47511 270)
			(size 0.519938 1.4986)
			(layers "F.Cu" "F.Mask" "F.Paste")
			(net "P12V_S3_AUX_CPU1_NVDIMM")
		)
		(pad "147" smd rect
			(at 2.050034 -61.624972 270)
			(size 0.519938 1.4986)
			(layers "F.Cu" "F.Mask" "F.Paste")
			(net "PWRGD_CHG_CPU1_DIMM2")
		)
		(pad "148" smd rect
			(at 2.050034 -60.775088 270)
			(size 0.519938 1.4986)
			(layers "F.Cu" "F.Mask" "F.Paste")
			(net "PD_CHG_CPU1_DIMM2_SAA")
		)
		(pad "149" smd rect
			(at 2.050034 -59.92495 270)
			(size 0.519938 1.4986)
			(layers "F.Cu" "F.Mask" "F.Paste")
			(net "TP_CHG_CPU1_DIMM2_FRU_2")
		)
		(pad "150" smd rect
			(at 2.050034 -59.075066 270)
			(size 0.519938 1.4986)
			(layers "F.Cu" "F.Mask" "F.Paste")
			(net "TP_CHG_CPU1_DIMM2_FRU_3")
		)
		(pad "151" smd rect
			(at 2.050034 -58.224928 270)
			(size 0.519938 1.4986)
			(layers "F.Cu" "F.Mask" "F.Paste")
			(net "GND")
		)
		(pad "152" smd rect
			(at 2.050034 -57.375044 270)
			(size 0.519938 1.4986)
			(layers "F.Cu" "F.Mask" "F.Paste")
			(net "M_G_CPU1_SA_DQ<2>")
		)
		(pad "153" smd rect
			(at 2.050034 -56.524906 270)
			(size 0.519938 1.4986)
			(layers "F.Cu" "F.Mask" "F.Paste")
			(net "GND")
		)
		(pad "154" smd rect
			(at 2.050034 -55.675022 270)
			(size 0.519938 1.4986)
			(layers "F.Cu" "F.Mask" "F.Paste")
			(net "M_G_CPU1_SA_DQ<3>")
		)
		(pad "155" smd rect
			(at 2.050034 -54.824884 270)
			(size 0.519938 1.4986)
			(layers "F.Cu" "F.Mask" "F.Paste")
			(net "GND")
		)
		(pad "156" smd rect
			(at 2.050034 -53.975 270)
			(size 0.519938 1.4986)
			(layers "F.Cu" "F.Mask" "F.Paste")
			(net "M_G_CPU1_SA_DQS_DN<5>")
		)
		(pad "157" smd rect
			(at 2.050034 -53.125116 270)
			(size 0.519938 1.4986)
			(layers "F.Cu" "F.Mask" "F.Paste")
			(net "M_G_CPU1_SA_DQS_DP<5>")
		)
		(pad "158" smd rect
			(at 2.050034 -52.274978 270)
			(size 0.519938 1.4986)
			(layers "F.Cu" "F.Mask" "F.Paste")
			(net "GND")
		)
		(pad "159" smd rect
			(at 2.050034 -51.425094 270)
			(size 0.519938 1.4986)
			(layers "F.Cu" "F.Mask" "F.Paste")
			(net "M_G_CPU1_SA_DQ<6>")
		)
		(pad "160" smd rect
			(at 2.050034 -50.574956 270)
			(size 0.519938 1.4986)
			(layers "F.Cu" "F.Mask" "F.Paste")
			(net "GND")
		)
		(pad "161" smd rect
			(at 2.050034 -49.725072 270)
			(size 0.519938 1.4986)
			(layers "F.Cu" "F.Mask" "F.Paste")
			(net "M_G_CPU1_SA_DQ<7>")
		)
		(pad "162" smd rect
			(at 2.050034 -48.874934 270)
			(size 0.519938 1.4986)
			(layers "F.Cu" "F.Mask" "F.Paste")
			(net "GND")
		)
		(pad "163" smd rect
			(at 2.050034 -48.02505 270)
			(size 0.519938 1.4986)
			(layers "F.Cu" "F.Mask" "F.Paste")
			(net "M_G_CPU1_SA_DQ<10>")
		)
		(pad "164" smd rect
			(at 2.050034 -47.174912 270)
			(size 0.519938 1.4986)
			(layers "F.Cu" "F.Mask" "F.Paste")
			(net "GND")
		)
		(pad "165" smd rect
			(at 2.050034 -46.325028 270)
			(size 0.519938 1.4986)
			(layers "F.Cu" "F.Mask" "F.Paste")
			(net "M_G_CPU1_SA_DQ<11>")
		)
		(pad "166" smd rect
			(at 2.050034 -45.47489 270)
			(size 0.519938 1.4986)
			(layers "F.Cu" "F.Mask" "F.Paste")
			(net "GND")
		)
		(pad "167" smd rect
			(at 2.050034 -44.625006 270)
			(size 0.519938 1.4986)
			(layers "F.Cu" "F.Mask" "F.Paste")
			(net "M_G_CPU1_SA_DQS_DN<6>")
		)
		(pad "168" smd rect
			(at 2.050034 -43.775122 270)
			(size 0.519938 1.4986)
			(layers "F.Cu" "F.Mask" "F.Paste")
			(net "M_G_CPU1_SA_DQS_DP<6>")
		)
		(pad "169" smd rect
			(at 2.050034 -42.924984 270)
			(size 0.519938 1.4986)
			(layers "F.Cu" "F.Mask" "F.Paste")
			(net "GND")
		)
		(pad "170" smd rect
			(at 2.050034 -42.0751 270)
			(size 0.519938 1.4986)
			(layers "F.Cu" "F.Mask" "F.Paste")
			(net "M_G_CPU1_SA_DQ<14>")
		)
		(pad "171" smd rect
			(at 2.050034 -41.224962 270)
			(size 0.519938 1.4986)
			(layers "F.Cu" "F.Mask" "F.Paste")
			(net "GND")
		)
		(pad "172" smd rect
			(at 2.050034 -40.375078 270)
			(size 0.519938 1.4986)
			(layers "F.Cu" "F.Mask" "F.Paste")
			(net "M_G_CPU1_SA_DQ<15>")
		)
		(pad "173" smd rect
			(at 2.050034 -39.52494 270)
			(size 0.519938 1.4986)
			(layers "F.Cu" "F.Mask" "F.Paste")
			(net "GND")
		)
		(pad "174" smd rect
			(at 2.050034 -38.675056 270)
			(size 0.519938 1.4986)
			(layers "F.Cu" "F.Mask" "F.Paste")
			(net "M_G_CPU1_SA_DQ<18>")
		)
		(pad "175" smd rect
			(at 2.050034 -37.824918 270)
			(size 0.519938 1.4986)
			(layers "F.Cu" "F.Mask" "F.Paste")
			(net "GND")
		)
		(pad "176" smd rect
			(at 2.050034 -36.975034 270)
			(size 0.519938 1.4986)
			(layers "F.Cu" "F.Mask" "F.Paste")
			(net "M_G_CPU1_SA_DQ<19>")
		)
		(pad "177" smd rect
			(at 2.050034 -36.124896 270)
			(size 0.519938 1.4986)
			(layers "F.Cu" "F.Mask" "F.Paste")
			(net "GND")
		)
		(pad "178" smd rect
			(at 2.050034 -35.275012 270)
			(size 0.519938 1.4986)
			(layers "F.Cu" "F.Mask" "F.Paste")
			(net "M_G_CPU1_SA_DQS_DN<7>")
		)
		(pad "179" smd rect
			(at 2.050034 -34.425128 270)
			(size 0.519938 1.4986)
			(layers "F.Cu" "F.Mask" "F.Paste")
			(net "M_G_CPU1_SA_DQS_DP<7>")
		)
		(pad "180" smd rect
			(at 2.050034 -33.57499 270)
			(size 0.519938 1.4986)
			(layers "F.Cu" "F.Mask" "F.Paste")
			(net "GND")
		)
		(pad "181" smd rect
			(at 2.050034 -32.725106 270)
			(size 0.519938 1.4986)
			(layers "F.Cu" "F.Mask" "F.Paste")
			(net "M_G_CPU1_SA_DQ<22>")
		)
		(pad "182" smd rect
			(at 2.050034 -31.874968 270)
			(size 0.519938 1.4986)
			(layers "F.Cu" "F.Mask" "F.Paste")
			(net "GND")
		)
	)
)
